# BASEBOARD_FAB2 (Tioga Pass) — schematic netlist excerpt (pin names and nets, part order shuffled) for the footprints in the layout excerpt that follows; sources: Cadence DE-HDL packaged netlist, KiCad conversion of Wiwynn_Tioga_Pass_MB.brd

R5D4  RES  240 1.0% CHIP  pkg 0402  page 90 : A = PVCCIO_CPU0 ; B = PU_CPU0_TXT_AGENT

Q8D2  FET_N  2N7002 FET  pkg SOT23LF  page 134
  GATE  = RST_PLTRST_BUF_N
  SRC  = FM_PCH_BMC_THERMTRIP_EXI_STRAP_
  DRN  = FM_PCH_BMC_THERMTRIP_N

C1T56  CAP_A  0.1UF 16V 10% X7R  pkg 0402V  page 155 : A = P3V3_STBY ; B = GND

(kicad_pcb
	(version 20260206)
	(generator "pcbnew")
	(generator_version "10.0")
	(general
		(thickness 1.6)
		(legacy_teardrops no)
	)
	(paper "A4")
	(title_block
		(title "Wiwynn_Tioga_Pass_MB.brd")
		(comment 1 "Tioga Pass / footprints 1779-1781 of 4770")
	)
	(layers
		(0 "F.Cu" signal "TOP")
		(4 "In1.Cu" signal "L2GND")
		(6 "In2.Cu" signal "L3")
		(8 "In3.Cu" signal "L4GND")
		(10 "In4.Cu" signal "L5")
		(12 "In5.Cu" signal "L6GND")
		(14 "In6.Cu" signal "L7VCC")
		(16 "In7.Cu" signal "L8VCC")
		(18 "In8.Cu" signal "L9GND")
		(20 "In9.Cu" signal "L10")
		(22 "In10.Cu" signal "L11GND")
		(24 "In11.Cu" signal "L12")
		(26 "In12.Cu" signal "L13GND")
		(2 "B.Cu" signal "BOTTOM")
		(9 "F.Adhes" user "F.Adhesive")
		(11 "B.Adhes" user "B.Adhesive")
		(13 "F.Paste" user "Package Geometry/Pastemask Top")
		(15 "B.Paste" user "Package Geometry/Pastemask Bottom")
		(5 "F.SilkS" user "Ref Des/Silkscreen Top")
		(7 "B.SilkS" user "Ref Des/Silkscreen Bottom")
		(1 "F.Mask" user "Board Geometry/Soldermask Top")
		(3 "B.Mask" user "Board Geometry/Soldermask Bottom")
		(17 "Dwgs.User" user "User.Drawings")
		(19 "Cmts.User" user "User.Comments")
		(21 "Eco1.User" user "User.Eco1")
		(23 "Eco2.User" user "User.Eco2")
		(25 "Edge.Cuts" user "Board Geometry/Outline")
		(27 "Margin" user)
		(31 "F.CrtYd" user "Package Geometry/Place Bound Top")
		(29 "B.CrtYd" user "Package Geometry/Place Bound Bottom")
		(35 "F.Fab" user "Ref Des/Assembly Top")
		(33 "B.Fab" user "Ref Des/Assembly Bottom")
	)
	(footprint ""
		(layer "F.Cu")
		(at 490.2835 -145.527268 -90)
		(property "Reference" "C1T56"
			(at 0 0 270)
			(layer "F.SilkS")
			(hide yes)
			(effects
				(font
					(size 1.27 1.27)
				)
			)
		)
		(property "Value" ""
			(at 0 0 270)
			(layer "F.Fab")
			(effects
				(font
					(size 1.27 1.27)
				)
			)
		)
		(duplicate_pad_numbers_are_jumpers no)
		(fp_poly
			(pts
				(xy 0.3048 -0.1016) (xy 0.3048 0.9906) (xy -0.3048 0.9906) (xy -0.3048 -0.1016)
			)
			(stroke
				(width 0)
				(type default)
			)
			(fill no)
			(layer "F.CrtYd")
		)
		(fp_line
			(start -0.3048 0.9906)
			(end 0.3048 0.9906)
			(stroke
				(width 0.1)
				(type default)
			)
			(layer "F.Fab")
		)
		(fp_line
			(start 0.3048 0.9906)
			(end 0.3048 -0.1016)
			(stroke
				(width 0.1)
				(type default)
			)
			(layer "F.Fab")
		)
		(fp_line
			(start -0.3048 -0.1016)
			(end -0.3048 0.9906)
			(stroke
				(width 0.1)
				(type default)
			)
			(layer "F.Fab")
		)
		(fp_line
			(start 0.3048 -0.1016)
			(end -0.3048 -0.1016)
			(stroke
				(width 0.1)
				(type default)
			)
			(layer "F.Fab")
		)
		(pad "1" smd rect
			(at 0 0 270)
			(size 0.508 0.508)
			(layers "F.Cu" "F.Mask" "F.Paste")
			(net "P3V3_STBY")
		)
		(pad "2" smd rect
			(at 0 0.889 270)
			(size 0.508 0.508)
			(layers "F.Cu" "F.Mask" "F.Paste")
			(net "GND")
		)
		(zone
			(layer "F.Cu")
			(hatch none 0.5)
			(connect_pads
				(clearance 0)
			)
			(min_thickness 0.25)
			(keepout
				(tracks not_allowed)
				(vias allowed)
				(pads allowed)
				(copperpour not_allowed)
				(footprints allowed)
			)
			(placement
				(enabled no)
				(sheetname "")
			)
			(fill
				(thermal_gap 0.5)
				(thermal_bridge_width 0.5)
				(island_removal_mode 0)
			)
			(polygon
				(pts
					(xy 489.6485 -145.781268) (xy 489.6485 -145.273268) (xy 490.0295 -145.273268) (xy 490.0295 -145.781268)
				)
			)
		)
		(zone
			(layer "F.Cu")
			(hatch none 0.5)
			(connect_pads
				(clearance 0)
			)
			(min_thickness 0.25)
			(keepout
				(tracks allowed)
				(vias not_allowed)
				(pads allowed)
				(copperpour not_allowed)
				(footprints allowed)
			)
			(placement
				(enabled no)
				(sheetname "")
			)
			(fill
				(thermal_gap 0.5)
				(thermal_bridge_width 0.5)
				(island_removal_mode 0)
			)
			(polygon
				(pts
					(xy 490.0295 -145.781268) (xy 490.0295 -145.273268) (xy 489.6485 -145.273268) (xy 489.6485 -145.781268)
				)
			)
		)
	)
	(footprint ""
		(layer "F.Cu")
		(at 275.463 -69.977)
		(property "Reference" "R5D4"
			(at 0 0 0)
			(layer "F.SilkS")
			(hide yes)
			(effects
				(font
					(size 1.27 1.27)
				)
			)
		)
		(property "Value" ""
			(at 0 0 0)
			(layer "F.Fab")
			(effects
				(font
					(size 1.27 1.27)
				)
			)
		)
		(duplicate_pad_numbers_are_jumpers no)
		(fp_poly
			(pts
				(xy -0.2794 -0.1016) (xy 0.2794 -0.1016) (xy 0.2794 0.9906) (xy -0.2794 0.9906)
			)
			(stroke
				(width 0)
				(type default)
			)
			(fill no)
			(layer "F.CrtYd")
		)
		(fp_line
			(start -0.2794 -0.1016)
			(end -0.2794 0.9906)
			(stroke
				(width 0.1)
				(type default)
			)
			(layer "F.Fab")
		)
		(fp_line
			(start -0.2794 0.9906)
			(end 0.2794 0.9906)
			(stroke
				(width 0.1)
				(type default)
			)
			(layer "F.Fab")
		)
		(fp_line
			(start 0.2794 -0.1016)
			(end -0.2794 -0.1016)
			(stroke
				(width 0.1)
				(type default)
			)
			(layer "F.Fab")
		)
		(fp_line
			(start 0.2794 0.9906)
			(end 0.2794 -0.1016)
			(stroke
				(width 0.1)
				(type default)
			)
			(layer "F.Fab")
		)
		(pad "1" smd rect
			(at 0 0)
			(size 0.508 0.508)
			(layers "F.Cu" "F.Mask" "F.Paste")
			(net "PVCCIO_CPU0")
		)
		(pad "2" smd rect
			(at 0 0.889)
			(size 0.508 0.508)
			(layers "F.Cu" "F.Mask" "F.Paste")
			(net "PU_CPU0_TXT_AGENT")
		)
		(zone
			(layer "F.Cu")
			(hatch none 0.5)
			(connect_pads
				(clearance 0)
			)
			(min_thickness 0.25)
			(keepout
				(tracks allowed)
				(vias not_allowed)
				(pads allowed)
				(copperpour not_allowed)
				(footprints allowed)
			)
			(placement
				(enabled no)
				(sheetname "")
			)
			(fill
				(thermal_gap 0.5)
				(thermal_bridge_width 0.5)
				(island_removal_mode 0)
			)
			(polygon
				(pts
					(xy 275.209 -69.723) (xy 275.717 -69.723) (xy 275.717 -69.342) (xy 275.209 -69.342)
				)
			)
		)
		(zone
			(layer "F.Cu")
			(hatch none 0.5)
			(connect_pads
				(clearance 0)
			)
			(min_thickness 0.25)
			(keepout
				(tracks not_allowed)
				(vias allowed)
				(pads allowed)
				(copperpour not_allowed)
				(footprints allowed)
			)
			(placement
				(enabled no)
				(sheetname "")
			)
			(fill
				(thermal_gap 0.5)
				(thermal_bridge_width 0.5)
				(island_removal_mode 0)
			)
			(polygon
				(pts
					(xy 275.209 -69.342) (xy 275.717 -69.342) (xy 275.717 -69.723) (xy 275.209 -69.723)
				)
			)
		)
	)
	(footprint ""
		(layer "F.Cu")
		(at 399.372074 -84.309204 -90)
		(property "Reference" "Q8D2"
			(at 1.42748 3.45567 90)
			(unlocked yes)
			(layer "F.SilkS")
			(effects
				(font
					(size 0.7874 0.5842)
					(thickness 0.1524)
				)
				(justify left)
			)
		)
		(property "Value" ""
			(at 0 0 270)
			(layer "F.Fab")
			(effects
				(font
					(size 1.27 1.27)
				)
			)
		)
		(duplicate_pad_numbers_are_jumpers no)
		(fp_line
			(start 0.9525 2.4765)
			(end 1.778 2.4765)
			(stroke
				(width 0.1524)
				(type default)
			)
			(layer "F.SilkS")
		)
		(fp_line
			(start 1.778 2.4765)
			(end 1.778 1.5875)
			(stroke
				(width 0.1524)
				(type default)
			)
			(layer "F.SilkS")
		)
		(fp_line
			(start 0.381 0.635)
			(end 0.381 1.27)
			(stroke
				(width 0.1524)
				(type default)
			)
			(layer "F.SilkS")
		)
		(fp_line
			(start 0.9525 -0.5715)
			(end 1.778 -0.5715)
			(stroke
				(width 0.1524)
				(type default)
			)
			(layer "F.SilkS")
		)
		(fp_line
			(start 1.778 -0.5715)
			(end 1.778 0.3175)
			(stroke
				(width 0.1524)
				(type default)
			)
			(layer "F.SilkS")
		)
		(fp_circle
			(center -1.039368 -0.721614)
			(end -1.039368 -0.848614)
			(stroke
				(width 0.254)
				(type default)
			)
			(fill no)
			(layer "F.SilkS")
		)
		(fp_poly
			(pts
				(xy 1.778 2.4765) (xy 0.381 2.4765) (xy 0.381 -0.5715) (xy 1.778 -0.5715)
			)
			(stroke
				(width 0)
				(type default)
			)
			(fill no)
			(layer "F.CrtYd")
		)
		(fp_line
			(start 0.381 2.4765)
			(end 1.778 2.4765)
			(stroke
				(width 0.1)
				(type default)
			)
			(layer "F.Fab")
		)
		(fp_line
			(start 1.778 2.4765)
			(end 1.778 -0.5715)
			(stroke
				(width 0.1)
				(type default)
			)
			(layer "F.Fab")
		)
		(fp_line
			(start 0.381 -0.5715)
			(end 0.381 2.4765)
			(stroke
				(width 0.1)
				(type default)
			)
			(layer "F.Fab")
		)
		(fp_line
			(start 1.778 -0.5715)
			(end 0.381 -0.5715)
			(stroke
				(width 0.1)
				(type default)
			)
			(layer "F.Fab")
		)
		(fp_circle
			(center -0.9525 -0.9271)
			(end -0.9525 -1.0541)
			(stroke
				(width 0.254)
				(type default)
			)
			(fill no)
			(layer "F.Fab")
		)
		(pad "1" smd rect
			(at 0 0 270)
			(size 1.143 0.508)
			(layers "F.Cu" "F.Mask" "F.Paste")
			(net "RST_PLTRST_BUF_N")
		)
		(pad "2" smd rect
			(at 0 1.905 270)
			(size 1.143 0.508)
			(layers "F.Cu" "F.Mask" "F.Paste")
			(net "FM_PCH_BMC_THERMTRIP_EXI_STRAP_")
		)
		(pad "3" smd rect
			(at 2.159 0.9525 270)
			(size 1.143 0.508)
			(layers "F.Cu" "F.Mask" "F.Paste")
			(net "FM_PCH_BMC_THERMTRIP_N")
		)
	)
)
